(kicad_pcb
	(version 20260206)
	(generator "pcbnew")
	(generator_version "10.0")
	(general
		(thickness 1.6)
		(legacy_teardrops no)
	)
	(paper "A4")
	(title_block
		(title "Wiwynn_Tioga_Pass_MB.brd")
		(comment 1 "Tioga Pass / footprints 125-130 of 4770")
	)
	(layers
		(0 "F.Cu" signal "TOP")
		(4 "In1.Cu" signal "L2GND")
		(6 "In2.Cu" signal "L3")
		(8 "In3.Cu" signal "L4GND")
		(10 "In4.Cu" signal "L5")
		(12 "In5.Cu" signal "L6GND")
		(14 "In6.Cu" signal "L7VCC")
		(16 "In7.Cu" signal "L8VCC")
		(18 "In8.Cu" signal "L9GND")
		(20 "In9.Cu" signal "L10")
		(22 "In10.Cu" signal "L11GND")
		(24 "In11.Cu" signal "L12")
		(26 "In12.Cu" signal "L13GND")
		(2 "B.Cu" signal "BOTTOM")
		(9 "F.Adhes" user "F.Adhesive")
		(11 "B.Adhes" user "B.Adhesive")
		(13 "F.Paste" user "Package Geometry/Pastemask Top")
		(15 "B.Paste" user "Package Geometry/Pastemask Bottom")
		(5 "F.SilkS" user "Ref Des/Silkscreen Top")
		(7 "B.SilkS" user "Ref Des/Silkscreen Bottom")
		(1 "F.Mask" user "Board Geometry/Soldermask Top")
		(3 "B.Mask" user "Board Geometry/Soldermask Bottom")
		(17 "Dwgs.User" user "User.Drawings")
		(19 "Cmts.User" user "User.Comments")
		(21 "Eco1.User" user "User.Eco1")
		(23 "Eco2.User" user "User.Eco2")
		(25 "Edge.Cuts" user "Board Geometry/Outline")
		(27 "Margin" user)
		(31 "F.CrtYd" user "Package Geometry/Place Bound Top")
		(29 "B.CrtYd" user "Package Geometry/Place Bound Bottom")
		(35 "F.Fab" user "Ref Des/Assembly Top")
		(33 "B.Fab" user "Ref Des/Assembly Bottom")
	)
	(footprint ""
		(layer "F.Cu")
		(at 270.890238 -68.365116 180)
		(property "Reference" "C5D60"
			(at 0 0 180)
			(layer "F.SilkS")
			(hide yes)
			(effects
				(font
					(size 1.27 1.27)
				)
			)
		)
		(property "Value" ""
			(at 0 0 180)
			(layer "F.Fab")
			(effects
				(font
					(size 1.27 1.27)
				)
			)
		)
		(duplicate_pad_numbers_are_jumpers no)
		(fp_poly
			(pts
				(xy -0.4953 -0.2032) (xy 0.4953 -0.2032) (xy 0.4953 1.6002) (xy -0.4953 1.6002)
			)
			(stroke
				(width 0)
				(type default)
			)
			(fill no)
			(layer "F.CrtYd")
		)
		(fp_line
			(start 0.4953 1.6002)
			(end -0.4953 1.6002)
			(stroke
				(width 0.1)
				(type default)
			)
			(layer "F.Fab")
		)
		(fp_line
			(start 0.4953 -0.2032)
			(end 0.4953 1.6002)
			(stroke
				(width 0.1)
				(type default)
			)
			(layer "F.Fab")
		)
		(fp_line
			(start -0.4953 1.6002)
			(end -0.4953 -0.2032)
			(stroke
				(width 0.1)
				(type default)
			)
			(layer "F.Fab")
		)
		(fp_line
			(start -0.4953 -0.2032)
			(end 0.4953 -0.2032)
			(stroke
				(width 0.1)
				(type default)
			)
			(layer "F.Fab")
		)
		(pad "1" smd rect
			(at 0 0 180)
			(size 0.762 0.889)
			(layers "F.Cu" "F.Mask" "F.Paste")
			(net "PVDDQ_ABC")
		)
		(pad "2" smd rect
			(at 0 1.397 180)
			(size 0.762 0.889)
			(layers "F.Cu" "F.Mask" "F.Paste")
			(net "GND")
		)
		(zone
			(layer "F.Cu")
			(hatch none 0.5)
			(connect_pads
				(clearance 0)
			)
			(min_thickness 0.25)
			(keepout
				(tracks not_allowed)
				(vias allowed)
				(pads allowed)
				(copperpour not_allowed)
				(footprints allowed)
			)
			(placement
				(enabled no)
				(sheetname "")
			)
			(fill
				(thermal_gap 0.5)
				(thermal_bridge_width 0.5)
				(island_removal_mode 0)
			)
			(polygon
				(pts
					(xy 271.271238 -68.809616) (xy 270.509238 -68.809616) (xy 270.509238 -69.317616) (xy 271.271238 -69.317616)
				)
			)
		)
	)
	(footprint ""
		(layer "F.Cu")
		(at 500.199914 -124.960126 90)
		(property "Reference" "S9W1"
			(at 0 0 90)
			(layer "F.SilkS")
			(hide yes)
			(effects
				(font
					(size 1.27 1.27)
				)
			)
		)
		(property "Value" "*"
			(at -6.092952 -8.046466 90)
			(unlocked yes)
			(layer "F.Fab")
			(hide yes)
			(effects
				(font
					(size 0.889 0.889)
					(thickness 0.1524)
				)
			)
		)
		(property "Device Type" "SW-SLIDE75-GP_DISCRET-G6-SW-SLA"
			(at -6.092952 -6.522466 90)
			(unlocked yes)
			(layer "F.Fab")
			(hide yes)
			(effects
				(font
					(size 0.889 0.889)
					(thickness 0.1524)
				)
			)
		)
		(duplicate_pad_numbers_are_jumpers no)
		(fp_line
			(start -2.0701 -2.8956)
			(end -2.4511 -2.8956)
			(stroke
				(width 0.3302)
				(type default)
			)
			(layer "F.SilkS")
		)
		(fp_line
			(start 4.4069 -2.7686)
			(end 4.4069 1.7272)
			(stroke
				(width 0.1524)
				(type default)
			)
			(layer "F.SilkS")
		)
		(fp_line
			(start -4.4069 -2.7686)
			(end 4.4069 -2.7686)
			(stroke
				(width 0.1524)
				(type default)
			)
			(layer "F.SilkS")
		)
		(fp_line
			(start 4.4069 1.7272)
			(end 1.651 1.7272)
			(stroke
				(width 0.1524)
				(type default)
			)
			(layer "F.SilkS")
		)
		(fp_line
			(start 1.651 1.7272)
			(end 1.651 3.048)
			(stroke
				(width 0.1524)
				(type default)
			)
			(layer "F.SilkS")
		)
		(fp_line
			(start -1.651 1.7272)
			(end -4.4069 1.7272)
			(stroke
				(width 0.1524)
				(type default)
			)
			(layer "F.SilkS")
		)
		(fp_line
			(start -4.4069 1.7272)
			(end -4.4069 -2.7686)
			(stroke
				(width 0.1524)
				(type default)
			)
			(layer "F.SilkS")
		)
		(fp_line
			(start 1.651 3.048)
			(end -1.651 3.048)
			(stroke
				(width 0.1524)
				(type default)
			)
			(layer "F.SilkS")
		)
		(fp_line
			(start -1.651 3.048)
			(end -1.651 1.7272)
			(stroke
				(width 0.1524)
				(type default)
			)
			(layer "F.SilkS")
		)
		(fp_poly
			(pts
				(xy -2.2606 -2.8194) (xy -2.6416 -3.2004) (xy -1.8796 -3.2004)
			)
			(stroke
				(width 0)
				(type default)
			)
			(fill yes)
			(layer "F.SilkS")
		)
		(fp_poly
			(pts
				(xy -1.397 2.794) (xy -1.397 1.2954) (xy -3.8481 1.2954) (xy -3.8481 -2.2098) (xy 3.8481 -2.2098)
				(xy 3.8481 1.2954) (xy 1.397 1.2954) (xy 1.397 2.794)
			)
			(stroke
				(width 0)
				(type default)
			)
			(fill no)
			(layer "F.CrtYd")
		)
		(fp_poly
			(pts
				(xy -0.3302 3.302) (xy -0.3302 2.794) (xy -1.397 2.794) (xy -1.397 1.2954) (xy -3.8481 1.2954) (xy -3.8481 -2.2098)
				(xy 3.8481 -2.2098) (xy 3.8481 1.2954) (xy 1.397 1.2954) (xy 1.397 2.794) (xy -0.3175 2.794) (xy -0.3175 3.302)
				(xy 1.905 3.302) (xy 1.905 1.9812) (xy 4.6609 1.9812) (xy 4.6609 -3.0226) (xy -4.6609 -3.0226) (xy -4.6609 1.9812)
				(xy -1.905 1.9812) (xy -1.905 3.302)
			)
			(stroke
				(width 0)
				(type default)
			)
			(fill no)
			(layer "F.CrtYd")
		)
		(fp_poly
			(pts
				(xy -1.905 3.302) (xy -1.905 1.9812) (xy -4.6609 1.9812) (xy -4.6609 -3.0226) (xy 4.6609 -3.0226)
				(xy 4.6609 1.9812) (xy 1.905 1.9812) (xy 1.905 3.302)
			)
			(stroke
				(width 0)
				(type default)
			)
			(fill no)
			(layer "F.Fab")
		)
		(pad "" np_thru_hole circle
			(at -1.49987 0 90)
			(size 0.254 0.254)
			(drill 0.9144)
			(layers "*.Cu" "*.Mask")
			(clearance 0.6858)
			(thermal_gap 0.6858)
		)
		(pad "" np_thru_hole circle
			(at 1.49987 0 90)
			(size 0.254 0.254)
			(drill 0.9144)
			(layers "*.Cu" "*.Mask")
			(clearance 0.6858)
			(thermal_gap 0.6858)
		)
		(pad "1" smd rect
			(at -2.25044 -1.75006 90)
			(size 0.7112 1.4986)
			(layers "F.Cu" "F.Mask" "F.Paste")
			(net "Net_6516")
		)
		(pad "2" smd rect
			(at 0.75057 -1.75006 90)
			(size 0.7112 1.4986)
			(layers "F.Cu" "F.Mask" "F.Paste")
			(net "BMC_JTAG_SEL")
		)
		(pad "3" smd rect
			(at 2.25044 -1.75006 90)
			(size 0.7112 1.4986)
			(layers "F.Cu" "F.Mask" "F.Paste")
			(net "GND")
		)
		(pad "4" smd rect
			(at -3.64998 -1.056386 90)
			(size 0.9906 0.8128)
			(layers "F.Cu" "F.Mask" "F.Paste")
			(net "GND")
		)
		(pad "5" smd rect
			(at -3.64998 1.056386 90)
			(size 0.9906 0.8128)
			(layers "F.Cu" "F.Mask" "F.Paste")
			(net "GND")
		)
		(pad "6" smd rect
			(at 3.64998 -1.056386 90)
			(size 0.9906 0.8128)
			(layers "F.Cu" "F.Mask" "F.Paste")
			(net "GND")
		)
		(pad "7" smd rect
			(at 3.64998 1.056386 90)
			(size 0.9906 0.8128)
			(layers "F.Cu" "F.Mask" "F.Paste")
			(net "GND")
		)
		(zone
			(layers "F.Cu" "B.Cu" "In1.Cu" "In2.Cu" "In3.Cu" "In4.Cu" "In5.Cu" "In6.Cu"
				"In7.Cu" "In8.Cu" "In9.Cu" "In10.Cu" "In11.Cu" "In12.Cu"
			)
			(hatch none 0.5)
			(connect_pads
				(clearance 0)
			)
			(min_thickness 0.25)
			(keepout
				(tracks not_allowed)
				(vias allowed)
				(pads allowed)
				(copperpour not_allowed)
				(footprints allowed)
			)
			(placement
				(enabled no)
				(sheetname "")
			)
			(fill
				(thermal_gap 0.5)
				(thermal_bridge_width 0.5)
				(island_removal_mode 0)
			)
			(polygon
				(pts
					(arc
						(start 500.961914 -126.459996)
						(mid 499.437914 -126.459996)
						(end 500.961914 -126.459996)
					)
				)
			)
		)
		(zone
			(layers "F.Cu" "B.Cu" "In1.Cu" "In2.Cu" "In3.Cu" "In4.Cu" "In5.Cu" "In6.Cu"
				"In7.Cu" "In8.Cu" "In9.Cu" "In10.Cu" "In11.Cu" "In12.Cu"
			)
			(hatch none 0.5)
			(connect_pads
				(clearance 0)
			)
			(min_thickness 0.25)
			(keepout
				(tracks not_allowed)
				(vias allowed)
				(pads allowed)
				(copperpour not_allowed)
				(footprints allowed)
			)
			(placement
				(enabled no)
				(sheetname "")
			)
			(fill
				(thermal_gap 0.5)
				(thermal_bridge_width 0.5)
				(island_removal_mode 0)
			)
			(polygon
				(pts
					(arc
						(start 500.961914 -123.460256)
						(mid 499.437914 -123.460256)
						(end 500.961914 -123.460256)
					)
				)
			)
		)
	)
	(footprint ""
		(layer "F.Cu")
		(at 162.38728 -68.8467 180)
		(property "Reference" "R3D20"
			(at 0 0 180)
			(layer "F.SilkS")
			(hide yes)
			(effects
				(font
					(size 1.27 1.27)
				)
			)
		)
		(property "Value" ""
			(at 0 0 180)
			(layer "F.Fab")
			(effects
				(font
					(size 1.27 1.27)
				)
			)
		)
		(duplicate_pad_numbers_are_jumpers no)
		(fp_poly
			(pts
				(xy -0.2794 -0.1016) (xy 0.2794 -0.1016) (xy 0.2794 0.9906) (xy -0.2794 0.9906)
			)
			(stroke
				(width 0)
				(type default)
			)
			(fill no)
			(layer "F.CrtYd")
		)
		(fp_line
			(start 0.2794 0.9906)
			(end 0.2794 -0.1016)
			(stroke
				(width 0.1)
				(type default)
			)
			(layer "F.Fab")
		)
		(fp_line
			(start 0.2794 -0.1016)
			(end -0.2794 -0.1016)
			(stroke
				(width 0.1)
				(type default)
			)
			(layer "F.Fab")
		)
		(fp_line
			(start -0.2794 0.9906)
			(end 0.2794 0.9906)
			(stroke
				(width 0.1)
				(type default)
			)
			(layer "F.Fab")
		)
		(fp_line
			(start -0.2794 -0.1016)
			(end -0.2794 0.9906)
			(stroke
				(width 0.1)
				(type default)
			)
			(layer "F.Fab")
		)
		(pad "1" smd rect
			(at 0 0 180)
			(size 0.508 0.508)
			(layers "F.Cu" "F.Mask" "F.Paste")
			(net "PVCCIO_CPU1")
		)
		(pad "2" smd rect
			(at 0 0.889 180)
			(size 0.508 0.508)
			(layers "F.Cu" "F.Mask" "F.Paste")
			(net "RST_CPU1_G_N")
		)
		(zone
			(layer "F.Cu")
			(hatch none 0.5)
			(connect_pads
				(clearance 0)
			)
			(min_thickness 0.25)
			(keepout
				(tracks not_allowed)
				(vias allowed)
				(pads allowed)
				(copperpour not_allowed)
				(footprints allowed)
			)
			(placement
				(enabled no)
				(sheetname "")
			)
			(fill
				(thermal_gap 0.5)
				(thermal_bridge_width 0.5)
				(island_removal_mode 0)
			)
			(polygon
				(pts
					(xy 162.64128 -69.4817) (xy 162.13328 -69.4817) (xy 162.13328 -69.1007) (xy 162.64128 -69.1007)
				)
			)
		)
		(zone
			(layer "F.Cu")
			(hatch none 0.5)
			(connect_pads
				(clearance 0)
			)
			(min_thickness 0.25)
			(keepout
				(tracks allowed)
				(vias not_allowed)
				(pads allowed)
				(copperpour not_allowed)
				(footprints allowed)
			)
			(placement
				(enabled no)
				(sheetname "")
			)
			(fill
				(thermal_gap 0.5)
				(thermal_bridge_width 0.5)
				(island_removal_mode 0)
			)
			(polygon
				(pts
					(xy 162.64128 -69.1007) (xy 162.13328 -69.1007) (xy 162.13328 -69.4817) (xy 162.64128 -69.4817)
				)
			)
		)
	)
	(footprint ""
		(layer "F.Cu")
		(at 412.5468 -102.489 180)
		(property "Reference" "R2N29"
			(at 0 0 180)
			(layer "F.SilkS")
			(hide yes)
			(effects
				(font
					(size 1.27 1.27)
				)
			)
		)
		(property "Value" ""
			(at 0 0 180)
			(layer "F.Fab")
			(effects
				(font
					(size 1.27 1.27)
				)
			)
		)
		(duplicate_pad_numbers_are_jumpers no)
		(fp_poly
			(pts
				(xy -0.2794 -0.1016) (xy 0.2794 -0.1016) (xy 0.2794 0.9906) (xy -0.2794 0.9906)
			)
			(stroke
				(width 0)
				(type default)
			)
			(fill no)
			(layer "F.CrtYd")
		)
		(fp_line
			(start 0.2794 0.9906)
			(end 0.2794 -0.1016)
			(stroke
				(width 0.1)
				(type default)
			)
			(layer "F.Fab")
		)
		(fp_line
			(start 0.2794 -0.1016)
			(end -0.2794 -0.1016)
			(stroke
				(width 0.1)
				(type default)
			)
			(layer "F.Fab")
		)
		(fp_line
			(start -0.2794 0.9906)
			(end 0.2794 0.9906)
			(stroke
				(width 0.1)
				(type default)
			)
			(layer "F.Fab")
		)
		(fp_line
			(start -0.2794 -0.1016)
			(end -0.2794 0.9906)
			(stroke
				(width 0.1)
				(type default)
			)
			(layer "F.Fab")
		)
		(pad "1" smd rect
			(at 0 0 180)
			(size 0.508 0.508)
			(layers "F.Cu" "F.Mask" "F.Paste")
			(net "P3V3_STBY")
		)
		(pad "2" smd rect
			(at 0 0.889 180)
			(size 0.508 0.508)
			(layers "F.Cu" "F.Mask" "F.Paste")
			(net "FM_CPU1_RC_ERROR_N")
		)
		(zone
			(layer "F.Cu")
			(hatch none 0.5)
			(connect_pads
				(clearance 0)
			)
			(min_thickness 0.25)
			(keepout
				(tracks not_allowed)
				(vias allowed)
				(pads allowed)
				(copperpour not_allowed)
				(footprints allowed)
			)
			(placement
				(enabled no)
				(sheetname "")
			)
			(fill
				(thermal_gap 0.5)
				(thermal_bridge_width 0.5)
				(island_removal_mode 0)
			)
			(polygon
				(pts
					(xy 412.8008 -103.124) (xy 412.2928 -103.124) (xy 412.2928 -102.743) (xy 412.8008 -102.743)
				)
			)
		)
		(zone
			(layer "F.Cu")
			(hatch none 0.5)
			(connect_pads
				(clearance 0)
			)
			(min_thickness 0.25)
			(keepout
				(tracks allowed)
				(vias not_allowed)
				(pads allowed)
				(copperpour not_allowed)
				(footprints allowed)
			)
			(placement
				(enabled no)
				(sheetname "")
			)
			(fill
				(thermal_gap 0.5)
				(thermal_bridge_width 0.5)
				(island_removal_mode 0)
			)
			(polygon
				(pts
					(xy 412.8008 -102.743) (xy 412.2928 -102.743) (xy 412.2928 -103.124) (xy 412.8008 -103.124)
				)
			)
		)
	)
	(footprint ""
		(layer "F.Cu")
		(at 402.971 -22.987)
		(property "Reference" "R25W90"
			(at -0.8382 -0.67818 0)
			(unlocked yes)
			(layer "F.SilkS")
			(effects
				(font
					(size 0.4064 0.254)
					(thickness 0.1524)
				)
				(justify left)
			)
		)
		(property "Value" ""
			(at 0 0 0)
			(layer "F.Fab")
			(effects
				(font
					(size 1.27 1.27)
				)
			)
		)
		(duplicate_pad_numbers_are_jumpers no)
		(fp_poly
			(pts
				(xy -0.2794 -0.1016) (xy 0.2794 -0.1016) (xy 0.2794 0.9906) (xy -0.2794 0.9906)
			)
			(stroke
				(width 0)
				(type default)
			)
			(fill no)
			(layer "F.CrtYd")
		)
		(fp_line
			(start -0.2794 -0.1016)
			(end -0.2794 0.9906)
			(stroke
				(width 0.1)
				(type default)
			)
			(layer "F.Fab")
		)
		(fp_line
			(start -0.2794 0.9906)
			(end 0.2794 0.9906)
			(stroke
				(width 0.1)
				(type default)
			)
			(layer "F.Fab")
		)
		(fp_line
			(start 0.2794 -0.1016)
			(end -0.2794 -0.1016)
			(stroke
				(width 0.1)
				(type default)
			)
			(layer "F.Fab")
		)
		(fp_line
			(start 0.2794 0.9906)
			(end 0.2794 -0.1016)
			(stroke
				(width 0.1)
				(type default)
			)
			(layer "F.Fab")
		)
		(pad "1" smd rect
			(at 0 0)
			(size 0.508 0.508)
			(layers "F.Cu" "F.Mask" "F.Paste")
			(net "RMII_BMC_PCH_SPRNGVLLE_TXD1_R")
		)
		(pad "2" smd rect
			(at 0 0.889)
			(size 0.508 0.508)
			(layers "F.Cu" "F.Mask" "F.Paste")
			(net "RMII_BMC_PCH_SPRNGVLLE_TXD1")
		)
		(zone
			(layer "F.Cu")
			(hatch none 0.5)
			(connect_pads
				(clearance 0)
			)
			(min_thickness 0.25)
			(keepout
				(tracks allowed)
				(vias not_allowed)
				(pads allowed)
				(copperpour not_allowed)
				(footprints allowed)
			)
			(placement
				(enabled no)
				(sheetname "")
			)
			(fill
				(thermal_gap 0.5)
				(thermal_bridge_width 0.5)
				(island_removal_mode 0)
			)
			(polygon
				(pts
					(xy 402.717 -22.733) (xy 403.225 -22.733) (xy 403.225 -22.352) (xy 402.717 -22.352)
				)
			)
		)
		(zone
			(layer "F.Cu")
			(hatch none 0.5)
			(connect_pads
				(clearance 0)
			)
			(min_thickness 0.25)
			(keepout
				(tracks not_allowed)
				(vias allowed)
				(pads allowed)
				(copperpour not_allowed)
				(footprints allowed)
			)
			(placement
				(enabled no)
				(sheetname "")
			)
			(fill
				(thermal_gap 0.5)
				(thermal_bridge_width 0.5)
				(island_removal_mode 0)
			)
			(polygon
				(pts
					(xy 402.717 -22.352) (xy 403.225 -22.352) (xy 403.225 -22.733) (xy 402.717 -22.733)
				)
			)
		)
	)
	(footprint ""
		(layer "F.Cu")
		(at 372.766844 -10.916158)
		(property "Reference" "C7G14"
			(at 0 0 0)
			(layer "F.SilkS")
			(hide yes)
			(effects
				(font
					(size 1.27 1.27)
				)
			)
		)
		(property "Value" ""
			(at 0 0 0)
			(layer "F.Fab")
			(effects
				(font
					(size 1.27 1.27)
				)
			)
		)
		(duplicate_pad_numbers_are_jumpers no)
		(fp_rect
			(start -0.3048 0.9906)
			(end 0.3048 -0.1016)
			(stroke
				(width 0)
				(type default)
			)
			(fill no)
			(layer "F.CrtYd")
		)
		(fp_line
			(start -0.3048 -0.1016)
			(end -0.3048 0.9906)
			(stroke
				(width 0.1)
				(type default)
			)
			(layer "F.Fab")
		)
		(fp_line
			(start -0.3048 0.9906)
			(end 0.3048 0.9906)
			(stroke
				(width 0.1)
				(type default)
			)
			(layer "F.Fab")
		)
		(fp_line
			(start 0.3048 -0.1016)
			(end -0.3048 -0.1016)
			(stroke
				(width 0.1)
				(type default)
			)
			(layer "F.Fab")
		)
		(fp_line
			(start 0.3048 0.9906)
			(end 0.3048 -0.1016)
			(stroke
				(width 0.1)
				(type default)
			)
			(layer "F.Fab")
		)
		(pad "1" smd rect
			(at 0 0)
			(size 0.508 0.508)
			(layers "F.Cu" "F.Mask" "F.Paste")
			(net "P3E_CPU0_PE2_SS_TXP<11>")
		)
		(pad "2" smd rect
			(at 0 0.889)
			(size 0.508 0.508)
			(layers "F.Cu" "F.Mask" "F.Paste")
			(net "P3E_CPU0_PE2_SS_C_TXP<11>")
		)
		(zone
			(layer "F.Cu")
			(hatch none 0.5)
			(connect_pads
				(clearance 0)
			)
			(min_thickness 0.25)
			(keepout
				(tracks allowed)
				(vias not_allowed)
				(pads allowed)
				(copperpour not_allowed)
				(footprints allowed)
			)
			(placement
				(enabled no)
				(sheetname "")
			)
			(fill
				(thermal_gap 0.5)
				(thermal_bridge_width 0.5)
				(island_removal_mode 0)
			)
			(polygon
				(pts
					(xy 372.512844 -10.281158) (xy 373.020844 -10.281158) (xy 373.020844 -10.662158) (xy 372.512844 -10.662158)
				)
			)
		)
		(zone
			(layer "F.Cu")
			(hatch none 0.5)
			(connect_pads
				(clearance 0)
			)
			(min_thickness 0.25)
			(keepout
				(tracks not_allowed)
				(vias allowed)
				(pads allowed)
				(copperpour not_allowed)
				(footprints allowed)
			)
			(placement
				(enabled no)
				(sheetname "")
			)
			(fill
				(thermal_gap 0.5)
				(thermal_bridge_width 0.5)
				(island_removal_mode 0)
			)
			(polygon
				(pts
					(xy 372.512844 -10.281158) (xy 373.020844 -10.281158) (xy 373.020844 -10.662158) (xy 372.512844 -10.662158)
				)
			)
		)
	)
)
